# T6G (Grand Teton) — schematic netlist excerpt (pin names and nets, part order shuffled) for the footprints in the layout excerpt that follows; sources: Cadence DE-HDL packaged netlist, KiCad conversion of 04192023_DAF0TMB3IC0_F0TG_MB_C_brd_V02_OCP.brd

PC6522  Q_CAP  22UF 16V 20% X6S  pkg C0805  page 361 : A = SW_P12V_AUX_P1V8_RETIMER_CPU1_FLT ; B = GND
PC209  Q_CAP  0.22UF 16V 10% X7R  pkg 0402  page 209 : A = SW_PVDD18_S5_P0_BST_R ; B = SW_PVDD18_S5_P0_SW
C807  Q_CAP_DIFFBUS  DIFF BUS_0.22UF 6.3V 20% X6S  pkg C0201  page 65 : \1\ = P5E_CPU1_P0_TX_C_DP<15> ; \2\ = P5E_CPU1_P0_TX_DP<15>
C6589  Q_CAP_DIFFBUS  DIFF BUS_0.22UF 6.3V 20% X6S  pkg C0201  page 297 : \1\ = P5E_CPU0_P2_TX_BUF_C_DP<12> ; \2\ = P5E_CPU0_P2_TX_BUF_DP<12>

(kicad_pcb
	(version 20260206)
	(generator "pcbnew")
	(generator_version "10.0")
	(general
		(thickness 1.6)
		(legacy_teardrops no)
	)
	(paper "A4")
	(title_block
		(title "04192023_DAF0TMB3IC0_F0TG_MB_C_brd_V02_OCP.brd")
		(comment 1 "Grand Teton / footprints 3232-3235 of 8354")
	)
	(layers
		(0 "F.Cu" signal "TOP")
		(4 "In1.Cu" signal "GND")
		(6 "In2.Cu" signal "IN1")
		(8 "In3.Cu" signal "GND1")
		(10 "In4.Cu" signal "IN2")
		(12 "In5.Cu" signal "GND2")
		(14 "In6.Cu" signal "IN3")
		(16 "In7.Cu" signal "GND3")
		(18 "In8.Cu" signal "VCC")
		(20 "In9.Cu" signal "VCC1")
		(22 "In10.Cu" signal "GND4")
		(24 "In11.Cu" signal "IN4")
		(26 "In12.Cu" signal "GND5")
		(28 "In13.Cu" signal "IN5")
		(30 "In14.Cu" signal "GND6")
		(32 "In15.Cu" signal "IN6")
		(34 "In16.Cu" signal "GND7")
		(2 "B.Cu" signal "BOTTOM")
		(9 "F.Adhes" user "F.Adhesive")
		(11 "B.Adhes" user "B.Adhesive")
		(13 "F.Paste" user "Package Geometry/Pastemask Top")
		(15 "B.Paste" user "Package Geometry/Pastemask Bottom")
		(5 "F.SilkS" user "Ref Des/Silkscreen Top")
		(7 "B.SilkS" user "Ref Des/Silkscreen Bottom")
		(1 "F.Mask" user "Board Geometry/Soldermask Top")
		(3 "B.Mask" user "Board Geometry/Soldermask Bottom")
		(17 "Dwgs.User" user "User.Drawings")
		(19 "Cmts.User" user "User.Comments")
		(21 "Eco1.User" user "User.Eco1")
		(23 "Eco2.User" user "User.Eco2")
		(25 "Edge.Cuts" user "Board Geometry/Outline")
		(27 "Margin" user)
		(31 "F.CrtYd" user "Package Geometry/Place Bound Top")
		(29 "B.CrtYd" user "Package Geometry/Place Bound Bottom")
		(35 "F.Fab" user "Ref Des/Assembly Top")
		(33 "B.Fab" user "Ref Des/Assembly Bottom")
	)
	(footprint ""
		(layer "F.Cu")
		(at 331.517498 -144.086834 90)
		(property "Reference" "PC209"
			(at 0 0 90)
			(layer "F.SilkS")
			(hide yes)
			(effects
				(font
					(size 1.27 1.27)
				)
			)
		)
		(property "Value" ""
			(at 0 0 90)
			(layer "F.Fab")
			(effects
				(font
					(size 1.27 1.27)
				)
			)
		)
		(duplicate_pad_numbers_are_jumpers no)
		(fp_line
			(start 0.7874 -0.4064)
			(end 0.7874 0.4064)
			(stroke
				(width 0.1524)
				(type default)
			)
			(layer "F.SilkS")
		)
		(fp_line
			(start -0.7874 -0.4064)
			(end 0.7874 -0.4064)
			(stroke
				(width 0.1524)
				(type default)
			)
			(layer "F.SilkS")
		)
		(fp_line
			(start 0.7874 0.4064)
			(end -0.7874 0.4064)
			(stroke
				(width 0.1524)
				(type default)
			)
			(layer "F.SilkS")
		)
		(fp_line
			(start -0.7874 0.4064)
			(end -0.7874 -0.4064)
			(stroke
				(width 0.1524)
				(type default)
			)
			(layer "F.SilkS")
		)
		(fp_line
			(start -0.12065 -0.305054)
			(end -0.12065 -0.2794)
			(stroke
				(width 0.1)
				(type default)
			)
			(layer "F.Fab")
		)
		(fp_line
			(start -0.67945 -0.305054)
			(end -0.12065 -0.305054)
			(stroke
				(width 0.1)
				(type default)
			)
			(layer "F.Fab")
		)
		(fp_line
			(start 0.67945 -0.3048)
			(end 0.67945 0.3048)
			(stroke
				(width 0.1)
				(type default)
			)
			(layer "F.Fab")
		)
		(fp_line
			(start 0.12065 -0.3048)
			(end 0.67945 -0.3048)
			(stroke
				(width 0.1)
				(type default)
			)
			(layer "F.Fab")
		)
		(fp_line
			(start 0.12065 -0.2794)
			(end 0.12065 -0.3048)
			(stroke
				(width 0.1)
				(type default)
			)
			(layer "F.Fab")
		)
		(fp_line
			(start -0.12065 -0.2794)
			(end 0.12065 -0.2794)
			(stroke
				(width 0.1)
				(type default)
			)
			(layer "F.Fab")
		)
		(fp_line
			(start 0.120396 0.2794)
			(end -0.12065 0.2794)
			(stroke
				(width 0.1)
				(type default)
			)
			(layer "F.Fab")
		)
		(fp_line
			(start -0.12065 0.2794)
			(end -0.12065 0.3048)
			(stroke
				(width 0.1)
				(type default)
			)
			(layer "F.Fab")
		)
		(fp_line
			(start 0.67945 0.3048)
			(end 0.120396 0.3048)
			(stroke
				(width 0.1)
				(type default)
			)
			(layer "F.Fab")
		)
		(fp_line
			(start 0.120396 0.3048)
			(end 0.120396 0.2794)
			(stroke
				(width 0.1)
				(type default)
			)
			(layer "F.Fab")
		)
		(fp_line
			(start -0.12065 0.3048)
			(end -0.67945 0.3048)
			(stroke
				(width 0.1)
				(type default)
			)
			(layer "F.Fab")
		)
		(fp_line
			(start -0.67945 0.3048)
			(end -0.67945 -0.305054)
			(stroke
				(width 0.1)
				(type default)
			)
			(layer "F.Fab")
		)
		(pad "1" smd circle
			(at -0.40005 0 90)
			(size 0 0)
			(layers "F.Cu" "F.Mask" "F.Paste")
			(net "SW_PVDD18_S5_P0_BST_R")
		)
		(pad "2" smd circle
			(at 0.40005 0 90)
			(size 0 0)
			(layers "F.Cu" "F.Mask" "F.Paste")
			(net "SW_PVDD18_S5_P0_SW")
		)
	)
	(footprint ""
		(layer "F.Cu")
		(at 408.541982 -416.899344 -90)
		(property "Reference" "C6589"
			(at 0 0 270)
			(layer "F.SilkS")
			(hide yes)
			(effects
				(font
					(size 1.27 1.27)
				)
			)
		)
		(property "Value" ""
			(at 0 0 270)
			(layer "F.Fab")
			(effects
				(font
					(size 1.27 1.27)
				)
			)
		)
		(duplicate_pad_numbers_are_jumpers no)
		(fp_line
			(start -0.299974 0.150114)
			(end -0.299974 -0.150114)
			(stroke
				(width 0.1)
				(type default)
			)
			(layer "F.Fab")
		)
		(fp_line
			(start 0.299974 0.150114)
			(end -0.299974 0.150114)
			(stroke
				(width 0.1)
				(type default)
			)
			(layer "F.Fab")
		)
		(fp_line
			(start -0.299974 -0.150114)
			(end 0.299974 -0.150114)
			(stroke
				(width 0.1)
				(type default)
			)
			(layer "F.Fab")
		)
		(fp_line
			(start 0.299974 -0.150114)
			(end 0.299974 0.150114)
			(stroke
				(width 0.1)
				(type default)
			)
			(layer "F.Fab")
		)
		(pad "1" smd rect
			(at -0.2667 0 270)
			(size 0.3048 0.381)
			(layers "F.Cu" "F.Mask" "F.Paste")
			(net "P5E_CPU0_P2_TX_BUF_C_DP<12>")
		)
		(pad "2" smd rect
			(at 0.2667 0 270)
			(size 0.3048 0.381)
			(layers "F.Cu" "F.Mask" "F.Paste")
			(net "P5E_CPU0_P2_TX_BUF_DP<12>")
		)
	)
	(footprint ""
		(layer "F.Cu")
		(at 69.741034 -379.471428)
		(property "Reference" "C807"
			(at 0 0 0)
			(layer "F.SilkS")
			(hide yes)
			(effects
				(font
					(size 1.27 1.27)
				)
			)
		)
		(property "Value" ""
			(at 0 0 0)
			(layer "F.Fab")
			(effects
				(font
					(size 1.27 1.27)
				)
			)
		)
		(duplicate_pad_numbers_are_jumpers no)
		(fp_line
			(start -0.299974 -0.150114)
			(end 0.299974 -0.150114)
			(stroke
				(width 0.1)
				(type default)
			)
			(layer "F.Fab")
		)
		(fp_line
			(start -0.299974 0.150114)
			(end -0.299974 -0.150114)
			(stroke
				(width 0.1)
				(type default)
			)
			(layer "F.Fab")
		)
		(fp_line
			(start 0.299974 -0.150114)
			(end 0.299974 0.150114)
			(stroke
				(width 0.1)
				(type default)
			)
			(layer "F.Fab")
		)
		(fp_line
			(start 0.299974 0.150114)
			(end -0.299974 0.150114)
			(stroke
				(width 0.1)
				(type default)
			)
			(layer "F.Fab")
		)
		(pad "1" smd rect
			(at -0.2667 0)
			(size 0.3048 0.381)
			(layers "F.Cu" "F.Mask" "F.Paste")
			(net "P5E_CPU1_P0_TX_C_DP<15>")
		)
		(pad "2" smd rect
			(at 0.2667 0)
			(size 0.3048 0.381)
			(layers "F.Cu" "F.Mask" "F.Paste")
			(net "P5E_CPU1_P0_TX_DP<15>")
		)
	)
	(footprint ""
		(layer "F.Cu")
		(at 233.2228 -285.2928)
		(property "Reference" "PC6522"
			(at 0 0 0)
			(layer "F.SilkS")
			(hide yes)
			(effects
				(font
					(size 1.27 1.27)
				)
			)
		)
		(property "Value" ""
			(at 0 0 0)
			(layer "F.Fab")
			(effects
				(font
					(size 1.27 1.27)
				)
			)
		)
		(duplicate_pad_numbers_are_jumpers no)
		(fp_line
			(start -1.524 -0.762)
			(end 1.524 -0.762)
			(stroke
				(width 0.1524)
				(type default)
			)
			(layer "F.SilkS")
		)
		(fp_line
			(start -1.524 0.762)
			(end -1.524 -0.762)
			(stroke
				(width 0.1524)
				(type default)
			)
			(layer "F.SilkS")
		)
		(fp_line
			(start 1.524 -0.762)
			(end 1.524 0.762)
			(stroke
				(width 0.1524)
				(type default)
			)
			(layer "F.SilkS")
		)
		(fp_line
			(start 1.524 0.762)
			(end -1.524 0.762)
			(stroke
				(width 0.1524)
				(type default)
			)
			(layer "F.SilkS")
		)
		(fp_line
			(start -1.1049 -0.724916)
			(end -1.1049 0.724916)
			(stroke
				(width 0.1)
				(type default)
			)
			(layer "F.Fab")
		)
		(fp_line
			(start -1.1049 0.724916)
			(end 1.1049 0.724916)
			(stroke
				(width 0.1)
				(type default)
			)
			(layer "F.Fab")
		)
		(fp_line
			(start 1.1049 -0.724916)
			(end -1.1049 -0.724916)
			(stroke
				(width 0.1)
				(type default)
			)
			(layer "F.Fab")
		)
		(fp_line
			(start 1.1049 0.724916)
			(end 1.1049 -0.724916)
			(stroke
				(width 0.1)
				(type default)
			)
			(layer "F.Fab")
		)
		(pad "1" smd rect
			(at -0.889 0 180)
			(size 1.016 1.27)
			(layers "F.Cu" "F.Mask" "F.Paste")
			(net "SW_P12V_AUX_P1V8_RETIMER_CPU1_FLT")
		)
		(pad "2" smd rect
			(at 0.889 0 180)
			(size 1.016 1.27)
			(layers "F.Cu" "F.Mask" "F.Paste")
			(net "GND")
		)
	)
)
